# S9S_MB_2U (Grand Teton) — schematic netlist excerpt (pin names and nets, part order shuffled) for the footprints in the layout excerpt that follows; sources: Cadence DE-HDL packaged netlist, KiCad conversion of 03242023_DA0F0TMBIJ0_F0T_Motherboard_J_brd_V01_OCP.brd

PC410_P1_1  Q_CAP  22UF 4V 20% X6S  pkg C0805  page 289 : A = PVCCFA_EHV_FIVRA_CPU1 ; B = GND
R1299  Q_RES  10K 1% CHIP  pkg 0402LF  page 200 : A = FM_MFG_MODE ; B = GND
R890  Q_RES  33.2 1% CHIP  pkg 0402LF  page 114 : A = PWRGD_CHG_CPU0_DIMM2 ; B = PWRGD_FAIL_CPU0_GH

(kicad_pcb
	(version 20260206)
	(generator "pcbnew")
	(generator_version "10.0")
	(general
		(thickness 1.6)
		(legacy_teardrops no)
	)
	(paper "A4")
	(title_block
		(title "03242023_DA0F0TMBIJ0_F0T_Motherboard_J_brd_V01_OCP.brd")
		(comment 1 "Grand Teton / footprints 5841-5843 of 6105")
	)
	(layers
		(0 "F.Cu" signal "TOP")
		(4 "In1.Cu" signal "GND")
		(6 "In2.Cu" signal "IN1")
		(8 "In3.Cu" signal "GND1")
		(10 "In4.Cu" signal "IN2")
		(12 "In5.Cu" signal "GND2")
		(14 "In6.Cu" signal "IN3")
		(16 "In7.Cu" signal "GND3")
		(18 "In8.Cu" signal "VCC")
		(20 "In9.Cu" signal "VCC1")
		(22 "In10.Cu" signal "GND4")
		(24 "In11.Cu" signal "IN4")
		(26 "In12.Cu" signal "GND5")
		(28 "In13.Cu" signal "IN5")
		(30 "In14.Cu" signal "GND6")
		(32 "In15.Cu" signal "IN6")
		(34 "In16.Cu" signal "GND7")
		(2 "B.Cu" signal "BOTTOM")
		(9 "F.Adhes" user "F.Adhesive")
		(11 "B.Adhes" user "B.Adhesive")
		(13 "F.Paste" user "Package Geometry/Pastemask Top")
		(15 "B.Paste" user "Package Geometry/Pastemask Bottom")
		(5 "F.SilkS" user "Ref Des/Silkscreen Top")
		(7 "B.SilkS" user "Ref Des/Silkscreen Bottom")
		(1 "F.Mask" user "Board Geometry/Soldermask Top")
		(3 "B.Mask" user "Board Geometry/Soldermask Bottom")
		(17 "Dwgs.User" user "User.Drawings")
		(19 "Cmts.User" user "User.Comments")
		(21 "Eco1.User" user "User.Eco1")
		(23 "Eco2.User" user "User.Eco2")
		(25 "Edge.Cuts" user "Board Geometry/Outline")
		(27 "Margin" user)
		(31 "F.CrtYd" user "Package Geometry/Place Bound Top")
		(29 "B.CrtYd" user "Package Geometry/Place Bound Bottom")
		(35 "F.Fab" user "Ref Des/Assembly Top")
		(33 "B.Fab" user "Ref Des/Assembly Bottom")
	)
	(footprint ""
		(layer "B.Cu")
		(at 440.617356 -318.933576 90)
		(property "Reference" "R890"
			(at 0 0 90)
			(layer "B.SilkS")
			(hide yes)
			(effects
				(font
					(size 1.27 1.27)
				)
				(justify mirror)
			)
		)
		(property "Value" ""
			(at 0 0 90)
			(layer "B.Fab")
			(effects
				(font
					(size 1.27 1.27)
				)
				(justify mirror)
			)
		)
		(duplicate_pad_numbers_are_jumpers no)
		(fp_line
			(start 0.7874 -0.4064)
			(end -0.7874 -0.4064)
			(stroke
				(width 0.1524)
				(type default)
			)
			(layer "B.SilkS")
		)
		(fp_line
			(start -0.7874 -0.4064)
			(end -0.7874 0.4064)
			(stroke
				(width 0.1524)
				(type default)
			)
			(layer "B.SilkS")
		)
		(fp_line
			(start 0.7874 0.4064)
			(end 0.7874 -0.4064)
			(stroke
				(width 0.1524)
				(type default)
			)
			(layer "B.SilkS")
		)
		(fp_line
			(start -0.7874 0.4064)
			(end 0.7874 0.4064)
			(stroke
				(width 0.1524)
				(type default)
			)
			(layer "B.SilkS")
		)
		(fp_line
			(start 0.67945 -0.305054)
			(end 0.12065 -0.305054)
			(stroke
				(width 0.1)
				(type default)
			)
			(layer "B.Fab")
		)
		(fp_line
			(start 0.12065 -0.305054)
			(end 0.12065 -0.2794)
			(stroke
				(width 0.1)
				(type default)
			)
			(layer "B.Fab")
		)
		(fp_line
			(start -0.12065 -0.3048)
			(end -0.67945 -0.3048)
			(stroke
				(width 0.1)
				(type default)
			)
			(layer "B.Fab")
		)
		(fp_line
			(start -0.67945 -0.3048)
			(end -0.67945 0.3048)
			(stroke
				(width 0.1)
				(type default)
			)
			(layer "B.Fab")
		)
		(fp_line
			(start 0.12065 -0.2794)
			(end -0.12065 -0.2794)
			(stroke
				(width 0.1)
				(type default)
			)
			(layer "B.Fab")
		)
		(fp_line
			(start -0.12065 -0.2794)
			(end -0.12065 -0.3048)
			(stroke
				(width 0.1)
				(type default)
			)
			(layer "B.Fab")
		)
		(fp_line
			(start 0.12065 0.2794)
			(end 0.12065 0.3048)
			(stroke
				(width 0.1)
				(type default)
			)
			(layer "B.Fab")
		)
		(fp_line
			(start -0.120396 0.2794)
			(end 0.12065 0.2794)
			(stroke
				(width 0.1)
				(type default)
			)
			(layer "B.Fab")
		)
		(fp_line
			(start 0.67945 0.3048)
			(end 0.67945 -0.305054)
			(stroke
				(width 0.1)
				(type default)
			)
			(layer "B.Fab")
		)
		(fp_line
			(start 0.12065 0.3048)
			(end 0.67945 0.3048)
			(stroke
				(width 0.1)
				(type default)
			)
			(layer "B.Fab")
		)
		(fp_line
			(start -0.120396 0.3048)
			(end -0.120396 0.2794)
			(stroke
				(width 0.1)
				(type default)
			)
			(layer "B.Fab")
		)
		(fp_line
			(start -0.67945 0.3048)
			(end -0.120396 0.3048)
			(stroke
				(width 0.1)
				(type default)
			)
			(layer "B.Fab")
		)
		(pad "1" smd circle
			(at 0.40005 0 270)
			(size 0 0)
			(layers "B.Cu" "B.Mask" "B.Paste")
			(net "PWRGD_CHG_CPU0_DIMM2")
		)
		(pad "2" smd circle
			(at -0.40005 0 270)
			(size 0 0)
			(layers "B.Cu" "B.Mask" "B.Paste")
			(net "PWRGD_FAIL_CPU0_GH")
		)
	)
	(footprint ""
		(layer "B.Cu")
		(at 309.558182 -32.243268 180)
		(property "Reference" "R1299"
			(at 0 0 0)
			(layer "B.SilkS")
			(hide yes)
			(effects
				(font
					(size 1.27 1.27)
				)
				(justify mirror)
			)
		)
		(property "Value" ""
			(at 0 0 0)
			(layer "B.Fab")
			(effects
				(font
					(size 1.27 1.27)
				)
				(justify mirror)
			)
		)
		(duplicate_pad_numbers_are_jumpers no)
		(fp_line
			(start 0.7874 0.4064)
			(end 0.7874 -0.4064)
			(stroke
				(width 0.1524)
				(type default)
			)
			(layer "B.SilkS")
		)
		(fp_line
			(start 0.7874 -0.4064)
			(end -0.7874 -0.4064)
			(stroke
				(width 0.1524)
				(type default)
			)
			(layer "B.SilkS")
		)
		(fp_line
			(start -0.7874 0.4064)
			(end 0.7874 0.4064)
			(stroke
				(width 0.1524)
				(type default)
			)
			(layer "B.SilkS")
		)
		(fp_line
			(start -0.7874 -0.4064)
			(end -0.7874 0.4064)
			(stroke
				(width 0.1524)
				(type default)
			)
			(layer "B.SilkS")
		)
		(fp_line
			(start 0.67945 0.3048)
			(end 0.67945 -0.305054)
			(stroke
				(width 0.1)
				(type default)
			)
			(layer "B.Fab")
		)
		(fp_line
			(start 0.67945 -0.305054)
			(end 0.12065 -0.305054)
			(stroke
				(width 0.1)
				(type default)
			)
			(layer "B.Fab")
		)
		(fp_line
			(start 0.12065 0.3048)
			(end 0.67945 0.3048)
			(stroke
				(width 0.1)
				(type default)
			)
			(layer "B.Fab")
		)
		(fp_line
			(start 0.12065 0.2794)
			(end 0.12065 0.3048)
			(stroke
				(width 0.1)
				(type default)
			)
			(layer "B.Fab")
		)
		(fp_line
			(start 0.12065 -0.2794)
			(end -0.12065 -0.2794)
			(stroke
				(width 0.1)
				(type default)
			)
			(layer "B.Fab")
		)
		(fp_line
			(start 0.12065 -0.305054)
			(end 0.12065 -0.2794)
			(stroke
				(width 0.1)
				(type default)
			)
			(layer "B.Fab")
		)
		(fp_line
			(start -0.120396 0.3048)
			(end -0.120396 0.2794)
			(stroke
				(width 0.1)
				(type default)
			)
			(layer "B.Fab")
		)
		(fp_line
			(start -0.120396 0.2794)
			(end 0.12065 0.2794)
			(stroke
				(width 0.1)
				(type default)
			)
			(layer "B.Fab")
		)
		(fp_line
			(start -0.12065 -0.2794)
			(end -0.12065 -0.3048)
			(stroke
				(width 0.1)
				(type default)
			)
			(layer "B.Fab")
		)
		(fp_line
			(start -0.12065 -0.3048)
			(end -0.67945 -0.3048)
			(stroke
				(width 0.1)
				(type default)
			)
			(layer "B.Fab")
		)
		(fp_line
			(start -0.67945 0.3048)
			(end -0.120396 0.3048)
			(stroke
				(width 0.1)
				(type default)
			)
			(layer "B.Fab")
		)
		(fp_line
			(start -0.67945 -0.3048)
			(end -0.67945 0.3048)
			(stroke
				(width 0.1)
				(type default)
			)
			(layer "B.Fab")
		)
		(pad "1" smd circle
			(at 0.40005 0)
			(size 0 0)
			(layers "B.Cu" "B.Mask" "B.Paste")
			(net "FM_MFG_MODE")
		)
		(pad "2" smd circle
			(at -0.40005 0)
			(size 0 0)
			(layers "B.Cu" "B.Mask" "B.Paste")
			(net "GND")
		)
	)
	(footprint ""
		(layer "B.Cu")
		(at 168.475152 -344.941906 -90)
		(property "Reference" "PC410_P1_1"
			(at 0 0 90)
			(layer "B.SilkS")
			(hide yes)
			(effects
				(font
					(size 1.27 1.27)
				)
				(justify mirror)
			)
		)
		(property "Value" ""
			(at 0 0 90)
			(layer "B.Fab")
			(effects
				(font
					(size 1.27 1.27)
				)
				(justify mirror)
			)
		)
		(duplicate_pad_numbers_are_jumpers no)
		(fp_line
			(start -1.524 0.762)
			(end 1.524 0.762)
			(stroke
				(width 0.1524)
				(type default)
			)
			(layer "B.SilkS")
		)
		(fp_line
			(start 1.524 0.762)
			(end 1.524 -0.762)
			(stroke
				(width 0.1524)
				(type default)
			)
			(layer "B.SilkS")
		)
		(fp_line
			(start -1.524 -0.762)
			(end -1.524 0.762)
			(stroke
				(width 0.1524)
				(type default)
			)
			(layer "B.SilkS")
		)
		(fp_line
			(start 1.524 -0.762)
			(end -1.524 -0.762)
			(stroke
				(width 0.1524)
				(type default)
			)
			(layer "B.SilkS")
		)
		(fp_line
			(start -1.1049 0.724916)
			(end -1.1049 -0.724916)
			(stroke
				(width 0.1)
				(type default)
			)
			(layer "B.Fab")
		)
		(fp_line
			(start 1.1049 0.724916)
			(end -1.1049 0.724916)
			(stroke
				(width 0.1)
				(type default)
			)
			(layer "B.Fab")
		)
		(fp_line
			(start -1.1049 -0.724916)
			(end 1.1049 -0.724916)
			(stroke
				(width 0.1)
				(type default)
			)
			(layer "B.Fab")
		)
		(fp_line
			(start 1.1049 -0.724916)
			(end 1.1049 0.724916)
			(stroke
				(width 0.1)
				(type default)
			)
			(layer "B.Fab")
		)
		(pad "1" smd rect
			(at 0.889 0 270)
			(size 1.016 1.27)
			(layers "B.Cu" "B.Mask" "B.Paste")
			(net "PVCCFA_EHV_FIVRA_CPU1")
		)
		(pad "2" smd rect
			(at -0.889 0 270)
			(size 1.016 1.27)
			(layers "B.Cu" "B.Mask" "B.Paste")
			(net "GND")
		)
	)
)
